# T6G (Grand Teton) — schematic netlist excerpt (pin names and nets, part order shuffled) for the footprints in the layout excerpt that follows; sources: Cadence DE-HDL packaged netlist, KiCad conversion of 04192023_DAF0TMB3IC0_F0TG_MB_C_brd_V02_OCP.brd

PC6574  Q_CAPP  390UF 2.5V 20% ALUM  pkg SMLF  page 363 : A = P0V9_CPU0_RT_2D ; B = GND
PC6507  Q_CAP  0.22UF 16V 10% X7R  pkg 0402  page 360 : A = SW_P1V8_RETIMER_CPU0_BST_R ; B = SW_P1V8_RETIMER_CPU0_SW

(kicad_pcb
	(version 20260206)
	(generator "pcbnew")
	(generator_version "10.0")
	(general
		(thickness 1.6)
		(legacy_teardrops no)
	)
	(paper "A4")
	(title_block
		(title "04192023_DAF0TMB3IC0_F0TG_MB_C_brd_V02_OCP.brd")
		(comment 1 "Grand Teton / footprints 3430-3431 of 8354")
	)
	(layers
		(0 "F.Cu" signal "TOP")
		(4 "In1.Cu" signal "GND")
		(6 "In2.Cu" signal "IN1")
		(8 "In3.Cu" signal "GND1")
		(10 "In4.Cu" signal "IN2")
		(12 "In5.Cu" signal "GND2")
		(14 "In6.Cu" signal "IN3")
		(16 "In7.Cu" signal "GND3")
		(18 "In8.Cu" signal "VCC")
		(20 "In9.Cu" signal "VCC1")
		(22 "In10.Cu" signal "GND4")
		(24 "In11.Cu" signal "IN4")
		(26 "In12.Cu" signal "GND5")
		(28 "In13.Cu" signal "IN5")
		(30 "In14.Cu" signal "GND6")
		(32 "In15.Cu" signal "IN6")
		(34 "In16.Cu" signal "GND7")
		(2 "B.Cu" signal "BOTTOM")
		(9 "F.Adhes" user "F.Adhesive")
		(11 "B.Adhes" user "B.Adhesive")
		(13 "F.Paste" user "Package Geometry/Pastemask Top")
		(15 "B.Paste" user "Package Geometry/Pastemask Bottom")
		(5 "F.SilkS" user "Ref Des/Silkscreen Top")
		(7 "B.SilkS" user "Ref Des/Silkscreen Bottom")
		(1 "F.Mask" user "Board Geometry/Soldermask Top")
		(3 "B.Mask" user "Board Geometry/Soldermask Bottom")
		(17 "Dwgs.User" user "User.Drawings")
		(19 "Cmts.User" user "User.Comments")
		(21 "Eco1.User" user "User.Eco1")
		(23 "Eco2.User" user "User.Eco2")
		(25 "Edge.Cuts" user "Board Geometry/Outline")
		(27 "Margin" user)
		(31 "F.CrtYd" user "Package Geometry/Place Bound Top")
		(29 "B.CrtYd" user "Package Geometry/Place Bound Bottom")
		(35 "F.Fab" user "Ref Des/Assembly Top")
		(33 "B.Fab" user "Ref Des/Assembly Bottom")
	)
	(footprint ""
		(layer "F.Cu")
		(at 449.955666 -380.13767 -90)
		(property "Reference" "PC6574"
			(at 4.75234 2.153666 0)
			(unlocked yes)
			(layer "F.SilkS")
			(effects
				(font
					(size 0.7874 0.5842)
					(thickness 0.1524)
				)
				(justify left)
			)
		)
		(property "Value" ""
			(at 0 0 270)
			(layer "F.Fab")
			(effects
				(font
					(size 1.27 1.27)
				)
			)
		)
		(duplicate_pad_numbers_are_jumpers no)
		(fp_line
			(start -1.988058 2.750058)
			(end 2.750058 2.750058)
			(stroke
				(width 0.1524)
				(type default)
			)
			(layer "F.SilkS")
		)
		(fp_line
			(start 2.750058 2.750058)
			(end 2.750058 0.9398)
			(stroke
				(width 0.1524)
				(type default)
			)
			(layer "F.SilkS")
		)
		(fp_line
			(start -2.750058 1.988058)
			(end -1.988058 2.750058)
			(stroke
				(width 0.1524)
				(type default)
			)
			(layer "F.SilkS")
		)
		(fp_line
			(start -2.750058 0.9398)
			(end -2.750058 1.988058)
			(stroke
				(width 0.1524)
				(type default)
			)
			(layer "F.SilkS")
		)
		(fp_line
			(start 2.750058 -0.9398)
			(end 2.750058 -2.750058)
			(stroke
				(width 0.1524)
				(type default)
			)
			(layer "F.SilkS")
		)
		(fp_line
			(start -2.750058 -1.988058)
			(end -2.750058 -0.9398)
			(stroke
				(width 0.1524)
				(type default)
			)
			(layer "F.SilkS")
		)
		(fp_line
			(start -1.988058 -2.750058)
			(end -2.750058 -1.988058)
			(stroke
				(width 0.1524)
				(type default)
			)
			(layer "F.SilkS")
		)
		(fp_line
			(start 2.750058 -2.750058)
			(end -1.988058 -2.750058)
			(stroke
				(width 0.1524)
				(type default)
			)
			(layer "F.SilkS")
		)
		(fp_line
			(start -2.750058 2.750058)
			(end 2.750058 2.750058)
			(stroke
				(width 0.1)
				(type default)
			)
			(layer "F.Fab")
		)
		(fp_line
			(start 2.750058 2.750058)
			(end 2.750058 -2.750058)
			(stroke
				(width 0.1)
				(type default)
			)
			(layer "F.Fab")
		)
		(fp_line
			(start -2.750058 -2.750058)
			(end -2.750058 2.750058)
			(stroke
				(width 0.1)
				(type default)
			)
			(layer "F.Fab")
		)
		(fp_line
			(start 2.750058 -2.750058)
			(end -2.750058 -2.750058)
			(stroke
				(width 0.1)
				(type default)
			)
			(layer "F.Fab")
		)
		(pad "1" smd rect
			(at -2.199894 0)
			(size 1.6002 3.0226)
			(layers "F.Cu" "F.Mask" "F.Paste")
			(net "P0V9_CPU0_RT_2D")
		)
		(pad "2" smd rect
			(at 2.199894 0)
			(size 1.6002 3.0226)
			(layers "F.Cu" "F.Mask" "F.Paste")
			(net "GND")
		)
	)
	(footprint ""
		(layer "F.Cu")
		(at 239.374426 -294.978074 90)
		(property "Reference" "PC6507"
			(at 0 0 90)
			(layer "F.SilkS")
			(hide yes)
			(effects
				(font
					(size 1.27 1.27)
				)
			)
		)
		(property "Value" ""
			(at 0 0 90)
			(layer "F.Fab")
			(effects
				(font
					(size 1.27 1.27)
				)
			)
		)
		(duplicate_pad_numbers_are_jumpers no)
		(fp_line
			(start 0.7874 -0.4064)
			(end 0.7874 0.4064)
			(stroke
				(width 0.1524)
				(type default)
			)
			(layer "F.SilkS")
		)
		(fp_line
			(start -0.7874 -0.4064)
			(end 0.7874 -0.4064)
			(stroke
				(width 0.1524)
				(type default)
			)
			(layer "F.SilkS")
		)
		(fp_line
			(start 0.7874 0.4064)
			(end -0.7874 0.4064)
			(stroke
				(width 0.1524)
				(type default)
			)
			(layer "F.SilkS")
		)
		(fp_line
			(start -0.7874 0.4064)
			(end -0.7874 -0.4064)
			(stroke
				(width 0.1524)
				(type default)
			)
			(layer "F.SilkS")
		)
		(fp_line
			(start -0.12065 -0.305054)
			(end -0.12065 -0.2794)
			(stroke
				(width 0.1)
				(type default)
			)
			(layer "F.Fab")
		)
		(fp_line
			(start -0.67945 -0.305054)
			(end -0.12065 -0.305054)
			(stroke
				(width 0.1)
				(type default)
			)
			(layer "F.Fab")
		)
		(fp_line
			(start 0.67945 -0.3048)
			(end 0.67945 0.3048)
			(stroke
				(width 0.1)
				(type default)
			)
			(layer "F.Fab")
		)
		(fp_line
			(start 0.12065 -0.3048)
			(end 0.67945 -0.3048)
			(stroke
				(width 0.1)
				(type default)
			)
			(layer "F.Fab")
		)
		(fp_line
			(start 0.12065 -0.2794)
			(end 0.12065 -0.3048)
			(stroke
				(width 0.1)
				(type default)
			)
			(layer "F.Fab")
		)
		(fp_line
			(start -0.12065 -0.2794)
			(end 0.12065 -0.2794)
			(stroke
				(width 0.1)
				(type default)
			)
			(layer "F.Fab")
		)
		(fp_line
			(start 0.120396 0.2794)
			(end -0.12065 0.2794)
			(stroke
				(width 0.1)
				(type default)
			)
			(layer "F.Fab")
		)
		(fp_line
			(start -0.12065 0.2794)
			(end -0.12065 0.3048)
			(stroke
				(width 0.1)
				(type default)
			)
			(layer "F.Fab")
		)
		(fp_line
			(start 0.67945 0.3048)
			(end 0.120396 0.3048)
			(stroke
				(width 0.1)
				(type default)
			)
			(layer "F.Fab")
		)
		(fp_line
			(start 0.120396 0.3048)
			(end 0.120396 0.2794)
			(stroke
				(width 0.1)
				(type default)
			)
			(layer "F.Fab")
		)
		(fp_line
			(start -0.12065 0.3048)
			(end -0.67945 0.3048)
			(stroke
				(width 0.1)
				(type default)
			)
			(layer "F.Fab")
		)
		(fp_line
			(start -0.67945 0.3048)
			(end -0.67945 -0.305054)
			(stroke
				(width 0.1)
				(type default)
			)
			(layer "F.Fab")
		)
		(pad "1" smd circle
			(at -0.40005 0 90)
			(size 0 0)
			(layers "F.Cu" "F.Mask" "F.Paste")
			(net "SW_P1V8_RETIMER_CPU0_BST_R")
		)
		(pad "2" smd circle
			(at 0.40005 0 90)
			(size 0 0)
			(layers "F.Cu" "F.Mask" "F.Paste")
			(net "SW_P1V8_RETIMER_CPU0_SW")
		)
	)
)
